(kicad_pcb
	(version 20260206)
	(generator "pcbnew")
	(generator_version "10.0")
	(general
		(thickness 1.6)
		(legacy_teardrops no)
	)
	(paper "A4")
	(title_block
		(title "04192023_DAF0TMB3IC0_F0TG_MB_C_brd_V02_OCP.brd")
		(comment 1 "Grand Teton / footprint 3955 of 8354 (U25), pads 2891-3002 of 6102")
	)
	(layers
		(0 "F.Cu" signal "TOP")
		(4 "In1.Cu" signal "GND")
		(6 "In2.Cu" signal "IN1")
		(8 "In3.Cu" signal "GND1")
		(10 "In4.Cu" signal "IN2")
		(12 "In5.Cu" signal "GND2")
		(14 "In6.Cu" signal "IN3")
		(16 "In7.Cu" signal "GND3")
		(18 "In8.Cu" signal "VCC")
		(20 "In9.Cu" signal "VCC1")
		(22 "In10.Cu" signal "GND4")
		(24 "In11.Cu" signal "IN4")
		(26 "In12.Cu" signal "GND5")
		(28 "In13.Cu" signal "IN5")
		(30 "In14.Cu" signal "GND6")
		(32 "In15.Cu" signal "IN6")
		(34 "In16.Cu" signal "GND7")
		(2 "B.Cu" signal "BOTTOM")
		(9 "F.Adhes" user "F.Adhesive")
		(11 "B.Adhes" user "B.Adhesive")
		(13 "F.Paste" user "Package Geometry/Pastemask Top")
		(15 "B.Paste" user "Package Geometry/Pastemask Bottom")
		(5 "F.SilkS" user "Ref Des/Silkscreen Top")
		(7 "B.SilkS" user "Ref Des/Silkscreen Bottom")
		(1 "F.Mask" user "Board Geometry/Soldermask Top")
		(3 "B.Mask" user "Board Geometry/Soldermask Bottom")
		(17 "Dwgs.User" user "User.Drawings")
		(19 "Cmts.User" user "User.Comments")
		(21 "Eco1.User" user "User.Eco1")
		(23 "Eco2.User" user "User.Eco2")
		(25 "Edge.Cuts" user "Board Geometry/Outline")
		(27 "Margin" user)
		(31 "F.CrtYd" user "Package Geometry/Place Bound Top")
		(29 "B.CrtYd" user "Package Geometry/Place Bound Bottom")
		(35 "F.Fab" user "Ref Des/Assembly Top")
		(33 "B.Fab" user "Ref Des/Assembly Bottom")
	)
	(footprint ""
		(layer "F.Cu")
		(at 359.867962 -258.880102 180)
		(property "Reference" "U25"
			(at -45.78477 -62.086744 0)
			(unlocked yes)
			(layer "F.SilkS")
			(effects
				(font
					(size 0.7874 0.5842)
					(thickness 0.1524)
				)
			)
		)
		(property "Value" ""
			(at 0 0 180)
			(layer "F.Fab")
			(effects
				(font
					(size 1.27 1.27)
				)
			)
		)
		(duplicate_pad_numbers_are_jumpers no)
		(pad "CB12" smd circle
			(at -24.589994 14.940026 180)
			(size 0.450088 0.450088)
			(layers "F.Cu" "F.Mask" "F.Paste")
			(net "GND")
		)
		(pad "CB13" smd circle
			(at -23.64994 14.940026 180)
			(size 0.450088 0.450088)
			(layers "F.Cu" "F.Mask" "F.Paste")
			(net "M_H_CPU0_SB_DQ<0>")
		)
		(pad "CB14" smd circle
			(at -22.709886 14.940026 180)
			(size 0.450088 0.450088)
			(layers "F.Cu" "F.Mask" "F.Paste")
			(net "M_H_CPU0_SB_CB<3>")
		)
		(pad "CB15" smd circle
			(at -21.770086 14.940026 180)
			(size 0.450088 0.450088)
			(layers "F.Cu" "F.Mask" "F.Paste")
			(net "GND")
		)
		(pad "CB16" smd circle
			(at -20.830032 14.940026 180)
			(size 0.450088 0.450088)
			(layers "F.Cu" "F.Mask" "F.Paste")
			(net "M_J_CPU0_SB_DQ<0>")
		)
		(pad "CB17" smd circle
			(at -19.889978 14.940026 180)
			(size 0.450088 0.450088)
			(layers "F.Cu" "F.Mask" "F.Paste")
			(net "GND")
		)
		(pad "CB18" smd circle
			(at -18.949924 14.940026 180)
			(size 0.450088 0.450088)
			(layers "F.Cu" "F.Mask" "F.Paste")
			(net "M_J_CPU0_SB_CB<3>")
		)
		(pad "CB19" smd circle
			(at -18.010124 14.940026 180)
			(size 0.450088 0.450088)
			(layers "F.Cu" "F.Mask" "F.Paste")
			(net "GND")
		)
		(pad "CB20" smd circle
			(at -17.07007 14.940026 180)
			(size 0.450088 0.450088)
			(layers "F.Cu" "F.Mask" "F.Paste")
			(net "M_I_CPU0_SB_DQ<0>")
		)
		(pad "CB21" smd circle
			(at -16.130016 14.940026 180)
			(size 0.450088 0.450088)
			(layers "F.Cu" "F.Mask" "F.Paste")
			(net "M_I_CPU0_SB_CB<3>")
		)
		(pad "CB22" smd circle
			(at -15.189962 14.940026 180)
			(size 0.450088 0.450088)
			(layers "F.Cu" "F.Mask" "F.Paste")
			(net "PVDD11_S3_P0")
		)
		(pad "CB23" smd circle
			(at -14.249908 14.940026 180)
			(size 0.450088 0.450088)
			(layers "F.Cu" "F.Mask" "F.Paste")
			(net "GND")
		)
		(pad "CB24" smd circle
			(at -13.310108 14.940026 180)
			(size 0.450088 0.450088)
			(layers "F.Cu" "F.Mask" "F.Paste")
			(net "GND")
		)
		(pad "CB25" smd circle
			(at -12.370054 14.940026 180)
			(size 0.450088 0.450088)
			(layers "F.Cu" "F.Mask" "F.Paste")
			(net "GND")
		)
		(pad "CB26" smd circle
			(at -11.43 14.940026 180)
			(size 0.450088 0.450088)
			(layers "F.Cu" "F.Mask" "F.Paste")
			(net "GND")
		)
		(pad "CB27" smd circle
			(at -10.489946 14.940026 180)
			(size 0.450088 0.450088)
			(layers "F.Cu" "F.Mask" "F.Paste")
			(net "GND")
		)
		(pad "CB28" smd circle
			(at -9.549892 14.940026 180)
			(size 0.450088 0.450088)
			(layers "F.Cu" "F.Mask" "F.Paste")
			(net "GND")
		)
		(pad "CB29" smd circle
			(at -8.610092 14.940026 180)
			(size 0.450088 0.450088)
			(layers "F.Cu" "F.Mask" "F.Paste")
			(net "GND")
		)
		(pad "CB30" smd circle
			(at -7.670038 14.940026 180)
			(size 0.450088 0.450088)
			(layers "F.Cu" "F.Mask" "F.Paste")
			(net "GND")
		)
		(pad "CB31" smd circle
			(at -6.729984 14.940026 180)
			(size 0.450088 0.450088)
			(layers "F.Cu" "F.Mask" "F.Paste")
			(net "GND")
		)
		(pad "CB32" smd circle
			(at -5.78993 14.940026 180)
			(size 0.450088 0.450088)
			(layers "F.Cu" "F.Mask" "F.Paste")
			(net "GND")
		)
		(pad "CB33" smd circle
			(at -4.849876 14.940026 180)
			(size 0.450088 0.450088)
			(layers "F.Cu" "F.Mask" "F.Paste")
			(net "GND")
		)
		(pad "CB34" smd circle
			(at -3.910076 14.940026 180)
			(size 0.450088 0.450088)
			(layers "F.Cu" "F.Mask" "F.Paste")
			(net "GND")
		)
		(pad "CB35" smd circle
			(at -2.970022 14.940026 180)
			(size 0.450088 0.450088)
			(layers "F.Cu" "F.Mask" "F.Paste")
			(net "P5E_CPU0_P2_TX_DN<2>")
		)
		(pad "CB36" smd circle
			(at -2.029968 14.940026 180)
			(size 0.450088 0.450088)
			(layers "F.Cu" "F.Mask" "F.Paste")
			(net "P5E_CPU0_P2_TX_DP<2>")
		)
		(pad "CB37" smd circle
			(at -1.089914 14.940026 180)
			(size 0.450088 0.450088)
			(layers "F.Cu" "F.Mask" "F.Paste")
			(net "GND")
		)
		(pad "CB39" smd circle
			(at 0.78994 14.940026 180)
			(size 0.450088 0.450088)
			(layers "F.Cu" "F.Mask" "F.Paste")
			(net "GND")
		)
		(pad "CB40" smd circle
			(at 1.729994 14.940026 180)
			(size 0.450088 0.450088)
			(layers "F.Cu" "F.Mask" "F.Paste")
			(net "P5E_CPU0_P0_RX_DP<13>")
		)
		(pad "CB41" smd circle
			(at 2.670048 14.940026 180)
			(size 0.450088 0.450088)
			(layers "F.Cu" "F.Mask" "F.Paste")
			(net "P5E_CPU0_P0_RX_DN<13>")
		)
		(pad "CB42" smd circle
			(at 3.610102 14.940026 180)
			(size 0.450088 0.450088)
			(layers "F.Cu" "F.Mask" "F.Paste")
			(net "GND")
		)
		(pad "CB43" smd circle
			(at 4.549902 14.940026 180)
			(size 0.450088 0.450088)
			(layers "F.Cu" "F.Mask" "F.Paste")
			(net "GND")
		)
		(pad "CB44" smd circle
			(at 5.489956 14.940026 180)
			(size 0.450088 0.450088)
			(layers "F.Cu" "F.Mask" "F.Paste")
			(net "GND")
		)
		(pad "CB45" smd circle
			(at 6.43001 14.940026 180)
			(size 0.450088 0.450088)
			(layers "F.Cu" "F.Mask" "F.Paste")
			(net "GND")
		)
		(pad "CB46" smd circle
			(at 7.370064 14.940026 180)
			(size 0.450088 0.450088)
			(layers "F.Cu" "F.Mask" "F.Paste")
			(net "GND")
		)
		(pad "CB47" smd circle
			(at 8.310118 14.940026 180)
			(size 0.450088 0.450088)
			(layers "F.Cu" "F.Mask" "F.Paste")
			(net "GND")
		)
		(pad "CB48" smd circle
			(at 9.249918 14.940026 180)
			(size 0.450088 0.450088)
			(layers "F.Cu" "F.Mask" "F.Paste")
			(net "GND")
		)
		(pad "CB49" smd circle
			(at 10.189972 14.940026 180)
			(size 0.450088 0.450088)
			(layers "F.Cu" "F.Mask" "F.Paste")
			(net "GND")
		)
		(pad "CB50" smd circle
			(at 11.130026 14.940026 180)
			(size 0.450088 0.450088)
			(layers "F.Cu" "F.Mask" "F.Paste")
			(net "GND")
		)
		(pad "CB51" smd circle
			(at 12.07008 14.940026 180)
			(size 0.450088 0.450088)
			(layers "F.Cu" "F.Mask" "F.Paste")
			(net "GND")
		)
		(pad "CB52" smd circle
			(at 13.00988 14.940026 180)
			(size 0.450088 0.450088)
			(layers "F.Cu" "F.Mask" "F.Paste")
			(net "GND")
		)
		(pad "CB53" smd circle
			(at 13.949934 14.940026 180)
			(size 0.450088 0.450088)
			(layers "F.Cu" "F.Mask" "F.Paste")
			(net "GND")
		)
		(pad "CB54" smd circle
			(at 14.889988 14.940026 180)
			(size 0.450088 0.450088)
			(layers "F.Cu" "F.Mask" "F.Paste")
			(net "PVDDIO_P0")
		)
		(pad "CB55" smd circle
			(at 15.830042 14.940026 180)
			(size 0.450088 0.450088)
			(layers "F.Cu" "F.Mask" "F.Paste")
			(net "M_C_CPU0_SB_CB<3>")
		)
		(pad "CB56" smd circle
			(at 16.770096 14.940026 180)
			(size 0.450088 0.450088)
			(layers "F.Cu" "F.Mask" "F.Paste")
			(net "M_C_CPU0_SB_DQ<0>")
		)
		(pad "CB57" smd circle
			(at 17.709896 14.940026 180)
			(size 0.450088 0.450088)
			(layers "F.Cu" "F.Mask" "F.Paste")
			(net "GND")
		)
		(pad "CB58" smd circle
			(at 18.64995 14.940026 180)
			(size 0.450088 0.450088)
			(layers "F.Cu" "F.Mask" "F.Paste")
			(net "M_D_CPU0_SB_CB<3>")
		)
		(pad "CB59" smd circle
			(at 19.590004 14.940026 180)
			(size 0.450088 0.450088)
			(layers "F.Cu" "F.Mask" "F.Paste")
			(net "GND")
		)
		(pad "CB60" smd circle
			(at 20.530058 14.940026 180)
			(size 0.450088 0.450088)
			(layers "F.Cu" "F.Mask" "F.Paste")
			(net "M_D_CPU0_SB_DQ<0>")
		)
		(pad "CB61" smd circle
			(at 21.470112 14.940026 180)
			(size 0.450088 0.450088)
			(layers "F.Cu" "F.Mask" "F.Paste")
			(net "GND")
		)
		(pad "CB62" smd circle
			(at 22.409912 14.940026 180)
			(size 0.450088 0.450088)
			(layers "F.Cu" "F.Mask" "F.Paste")
			(net "M_B_CPU0_SB_CB<3>")
		)
		(pad "CB63" smd circle
			(at 23.349966 14.940026 180)
			(size 0.450088 0.450088)
			(layers "F.Cu" "F.Mask" "F.Paste")
			(net "M_B_CPU0_SB_DQ<0>")
		)
		(pad "CB64" smd circle
			(at 24.29002 14.940026 180)
			(size 0.450088 0.450088)
			(layers "F.Cu" "F.Mask" "F.Paste")
			(net "GND")
		)
		(pad "CB65" smd circle
			(at 25.230074 14.940026 180)
			(size 0.450088 0.450088)
			(layers "F.Cu" "F.Mask" "F.Paste")
			(net "M_F_CPU0_SB_CB<3>")
		)
		(pad "CB66" smd circle
			(at 26.170128 14.940026 180)
			(size 0.450088 0.450088)
			(layers "F.Cu" "F.Mask" "F.Paste")
			(net "GND")
		)
		(pad "CB67" smd circle
			(at 27.109928 14.940026 180)
			(size 0.450088 0.450088)
			(layers "F.Cu" "F.Mask" "F.Paste")
			(net "M_F_CPU0_SB_DQ<0>")
		)
		(pad "CB68" smd circle
			(at 28.049982 14.940026 180)
			(size 0.450088 0.450088)
			(layers "F.Cu" "F.Mask" "F.Paste")
			(net "GND")
		)
		(pad "CB69" smd circle
			(at 28.990036 14.940026 180)
			(size 0.450088 0.450088)
			(layers "F.Cu" "F.Mask" "F.Paste")
			(net "M_E_CPU0_SB_CB<3>")
		)
		(pad "CB70" smd circle
			(at 29.93009 14.940026 180)
			(size 0.450088 0.450088)
			(layers "F.Cu" "F.Mask" "F.Paste")
			(net "M_E_CPU0_SB_DQ<0>")
		)
		(pad "CB71" smd circle
			(at 30.86989 14.940026 180)
			(size 0.450088 0.450088)
			(layers "F.Cu" "F.Mask" "F.Paste")
			(net "GND")
		)
		(pad "CB72" smd circle
			(at 31.809944 14.940026 180)
			(size 0.450088 0.450088)
			(layers "F.Cu" "F.Mask" "F.Paste")
			(net "M_A_CPU0_SB_CB<3>")
		)
		(pad "CB73" smd circle
			(at 32.749998 14.940026 180)
			(size 0.450088 0.450088)
			(layers "F.Cu" "F.Mask" "F.Paste")
			(net "GND")
		)
		(pad "CB74" smd circle
			(at 33.690052 14.940026 180)
			(size 0.450088 0.450088)
			(layers "F.Cu" "F.Mask" "F.Paste")
			(net "M_A_CPU0_SB_DQ<0>")
		)
		(pad "CC1" smd circle
			(at -34.459926 15.750032 180)
			(size 0.450088 0.450088)
			(layers "F.Cu" "F.Mask" "F.Paste")
			(net "GND")
		)
		(pad "CC2" smd circle
			(at -33.519872 15.750032 180)
			(size 0.450088 0.450088)
			(layers "F.Cu" "F.Mask" "F.Paste")
			(net "M_G_CPU0_SB_DQ<2>")
		)
		(pad "CC3" smd circle
			(at -32.580072 15.750032 180)
			(size 0.450088 0.450088)
			(layers "F.Cu" "F.Mask" "F.Paste")
			(net "M_G_CPU0_SB_DQ<1>")
		)
		(pad "CC4" smd circle
			(at -31.640018 15.750032 180)
			(size 0.450088 0.450088)
			(layers "F.Cu" "F.Mask" "F.Paste")
			(net "GND")
		)
		(pad "CC5" smd circle
			(at -30.699964 15.750032 180)
			(size 0.450088 0.450088)
			(layers "F.Cu" "F.Mask" "F.Paste")
			(net "M_K_CPU0_SB_DQ<2>")
		)
		(pad "CC6" smd circle
			(at -29.75991 15.750032 180)
			(size 0.450088 0.450088)
			(layers "F.Cu" "F.Mask" "F.Paste")
			(net "GND")
		)
		(pad "CC7" smd circle
			(at -28.82011 15.750032 180)
			(size 0.450088 0.450088)
			(layers "F.Cu" "F.Mask" "F.Paste")
			(net "M_K_CPU0_SB_DQ<1>")
		)
		(pad "CC8" smd circle
			(at -27.880056 15.750032 180)
			(size 0.450088 0.450088)
			(layers "F.Cu" "F.Mask" "F.Paste")
			(net "GND")
		)
		(pad "CC9" smd circle
			(at -26.940002 15.750032 180)
			(size 0.450088 0.450088)
			(layers "F.Cu" "F.Mask" "F.Paste")
			(net "M_L_CPU0_SB_DQ<2>")
		)
		(pad "CC10" smd circle
			(at -25.999948 15.750032 180)
			(size 0.450088 0.450088)
			(layers "F.Cu" "F.Mask" "F.Paste")
			(net "M_L_CPU0_SB_DQ<1>")
		)
		(pad "CC11" smd circle
			(at -25.059894 15.750032 180)
			(size 0.450088 0.450088)
			(layers "F.Cu" "F.Mask" "F.Paste")
			(net "GND")
		)
		(pad "CC12" smd circle
			(at -24.120094 15.750032 180)
			(size 0.450088 0.450088)
			(layers "F.Cu" "F.Mask" "F.Paste")
			(net "M_H_CPU0_SB_DQ<2>")
		)
		(pad "CC13" smd circle
			(at -23.18004 15.750032 180)
			(size 0.450088 0.450088)
			(layers "F.Cu" "F.Mask" "F.Paste")
			(net "GND")
		)
		(pad "CC14" smd circle
			(at -22.239986 15.750032 180)
			(size 0.450088 0.450088)
			(layers "F.Cu" "F.Mask" "F.Paste")
			(net "M_H_CPU0_SB_DQ<1>")
		)
		(pad "CC15" smd circle
			(at -21.299932 15.750032 180)
			(size 0.450088 0.450088)
			(layers "F.Cu" "F.Mask" "F.Paste")
			(net "GND")
		)
		(pad "CC16" smd circle
			(at -20.359878 15.750032 180)
			(size 0.450088 0.450088)
			(layers "F.Cu" "F.Mask" "F.Paste")
			(net "M_J_CPU0_SB_DQ<2>")
		)
		(pad "CC17" smd circle
			(at -19.420078 15.750032 180)
			(size 0.450088 0.450088)
			(layers "F.Cu" "F.Mask" "F.Paste")
			(net "M_J_CPU0_SB_DQ<1>")
		)
		(pad "CC18" smd circle
			(at -18.480024 15.750032 180)
			(size 0.450088 0.450088)
			(layers "F.Cu" "F.Mask" "F.Paste")
			(net "GND")
		)
		(pad "CC19" smd circle
			(at -17.53997 15.750032 180)
			(size 0.450088 0.450088)
			(layers "F.Cu" "F.Mask" "F.Paste")
			(net "M_I_CPU0_SB_DQ<2>")
		)
		(pad "CC20" smd circle
			(at -16.599916 15.750032 180)
			(size 0.450088 0.450088)
			(layers "F.Cu" "F.Mask" "F.Paste")
			(net "GND")
		)
		(pad "CC21" smd circle
			(at -15.660116 15.750032 180)
			(size 0.450088 0.450088)
			(layers "F.Cu" "F.Mask" "F.Paste")
			(net "M_I_CPU0_SB_DQ<1>")
		)
		(pad "CC22" smd circle
			(at -14.720062 15.750032 180)
			(size 0.450088 0.450088)
			(layers "F.Cu" "F.Mask" "F.Paste")
			(net "GND")
		)
		(pad "CC23" smd circle
			(at -13.780008 15.750032 180)
			(size 0.450088 0.450088)
			(layers "F.Cu" "F.Mask" "F.Paste")
			(net "P5E_CPU0_P3_TX_DN<13>")
		)
		(pad "CC24" smd circle
			(at -12.839954 15.750032 180)
			(size 0.450088 0.450088)
			(layers "F.Cu" "F.Mask" "F.Paste")
			(net "P5E_CPU0_P3_TX_DP<13>")
		)
		(pad "CC25" smd circle
			(at -11.8999 15.750032 180)
			(size 0.450088 0.450088)
			(layers "F.Cu" "F.Mask" "F.Paste")
			(net "GND")
		)
		(pad "CC26" smd circle
			(at -10.9601 15.750032 180)
			(size 0.450088 0.450088)
			(layers "F.Cu" "F.Mask" "F.Paste")
			(net "P5E_CPU0_P3_TX_DN<10>")
		)
		(pad "CC27" smd circle
			(at -10.020046 15.750032 180)
			(size 0.450088 0.450088)
			(layers "F.Cu" "F.Mask" "F.Paste")
			(net "P5E_CPU0_P3_TX_DP<10>")
		)
		(pad "CC28" smd circle
			(at -9.079992 15.750032 180)
			(size 0.450088 0.450088)
			(layers "F.Cu" "F.Mask" "F.Paste")
			(net "GND")
		)
		(pad "CC29" smd circle
			(at -8.139938 15.750032 180)
			(size 0.450088 0.450088)
			(layers "F.Cu" "F.Mask" "F.Paste")
			(net "P5E_CPU0_P3_TX_DN<7>")
		)
		(pad "CC30" smd circle
			(at -7.199884 15.750032 180)
			(size 0.450088 0.450088)
			(layers "F.Cu" "F.Mask" "F.Paste")
			(net "P5E_CPU0_P3_TX_DP<7>")
		)
		(pad "CC31" smd circle
			(at -6.260084 15.750032 180)
			(size 0.450088 0.450088)
			(layers "F.Cu" "F.Mask" "F.Paste")
			(net "GND")
		)
		(pad "CC32" smd circle
			(at -5.32003 15.750032 180)
			(size 0.450088 0.450088)
			(layers "F.Cu" "F.Mask" "F.Paste")
			(net "P5E_CPU0_P3_TX_DN<3>")
		)
		(pad "CC33" smd circle
			(at -4.379976 15.750032 180)
			(size 0.450088 0.450088)
			(layers "F.Cu" "F.Mask" "F.Paste")
			(net "P5E_CPU0_P3_TX_DP<3>")
		)
		(pad "CC34" smd circle
			(at -3.439922 15.750032 180)
			(size 0.450088 0.450088)
			(layers "F.Cu" "F.Mask" "F.Paste")
			(net "GND")
		)
		(pad "CC35" smd circle
			(at -2.500122 15.750032 180)
			(size 0.450088 0.450088)
			(layers "F.Cu" "F.Mask" "F.Paste")
			(net "PVDDCR_CPU1_P0")
		)
		(pad "CC36" smd circle
			(at -1.560068 15.750032 180)
			(size 0.450088 0.450088)
			(layers "F.Cu" "F.Mask" "F.Paste")
			(net "PVDDCR_CPU1_P0")
		)
		(pad "CC40" smd circle
			(at 1.260094 15.750032 180)
			(size 0.450088 0.450088)
			(layers "F.Cu" "F.Mask" "F.Paste")
			(net "PVDDCR_CPU1_P0")
		)
		(pad "CC41" smd circle
			(at 2.199894 15.750032 180)
			(size 0.450088 0.450088)
			(layers "F.Cu" "F.Mask" "F.Paste")
			(net "PVDDCR_CPU1_P0")
		)
		(pad "CC42" smd circle
			(at 3.139948 15.750032 180)
			(size 0.450088 0.450088)
			(layers "F.Cu" "F.Mask" "F.Paste")
			(net "GND")
		)
		(pad "CC43" smd circle
			(at 4.080002 15.750032 180)
			(size 0.450088 0.450088)
			(layers "F.Cu" "F.Mask" "F.Paste")
			(net "P5E_CPU0_P1_RX_DP<12>")
		)
		(pad "CC44" smd circle
			(at 5.020056 15.750032 180)
			(size 0.450088 0.450088)
			(layers "F.Cu" "F.Mask" "F.Paste")
			(net "P5E_CPU0_P1_RX_DN<12>")
		)
		(pad "CC45" smd circle
			(at 5.96011 15.750032 180)
			(size 0.450088 0.450088)
			(layers "F.Cu" "F.Mask" "F.Paste")
			(net "GND")
		)
		(pad "CC46" smd circle
			(at 6.89991 15.750032 180)
			(size 0.450088 0.450088)
			(layers "F.Cu" "F.Mask" "F.Paste")
			(net "P5E_CPU0_P1_RX_DP<8>")
		)
		(pad "CC47" smd circle
			(at 7.839964 15.750032 180)
			(size 0.450088 0.450088)
			(layers "F.Cu" "F.Mask" "F.Paste")
			(net "P5E_CPU0_P1_RX_DN<8>")
		)
		(pad "CC48" smd circle
			(at 8.780018 15.750032 180)
			(size 0.450088 0.450088)
			(layers "F.Cu" "F.Mask" "F.Paste")
			(net "GND")
		)
		(pad "CC49" smd circle
			(at 9.720072 15.750032 180)
			(size 0.450088 0.450088)
			(layers "F.Cu" "F.Mask" "F.Paste")
			(net "P5E_CPU0_P1_RX_DP<5>")
		)
		(pad "CC50" smd circle
			(at 10.659872 15.750032 180)
			(size 0.450088 0.450088)
			(layers "F.Cu" "F.Mask" "F.Paste")
			(net "P5E_CPU0_P1_RX_DN<5>")
		)
		(pad "CC51" smd circle
			(at 11.599926 15.750032 180)
			(size 0.450088 0.450088)
			(layers "F.Cu" "F.Mask" "F.Paste")
			(net "GND")
		)
		(pad "CC52" smd circle
			(at 12.53998 15.750032 180)
			(size 0.450088 0.450088)
			(layers "F.Cu" "F.Mask" "F.Paste")
			(net "P5E_CPU0_P1_RX_DP<2>")
		)
		(pad "CC53" smd circle
			(at 13.480034 15.750032 180)
			(size 0.450088 0.450088)
			(layers "F.Cu" "F.Mask" "F.Paste")
			(net "P5E_CPU0_P1_RX_DN<2>")
		)
	)
)
